(kicad_pcb
	(version 20241229)
	(generator "pcbnew")
	(generator_version "9.0")
	(general
		(thickness 1.599998)
		(legacy_teardrops no)
	)
	(paper "A4")
	(title_block
		(title "Artix - Datacenter Secure Control Module (DC-SCM)")
		(date "2024-11-06")
		(rev "1.1.3")
		(comment 9 "footprints 180-185 of 544")
	)
	(layers
		(0 "F.Cu" signal)
		(4 "In1.Cu" signal)
		(6 "In2.Cu" signal)
		(8 "In3.Cu" signal)
		(10 "In4.Cu" signal)
		(12 "In5.Cu" signal)
		(14 "In6.Cu" signal)
		(2 "B.Cu" signal)
		(9 "F.Adhes" user "F.Adhesive")
		(11 "B.Adhes" user "B.Adhesive")
		(13 "F.Paste" user)
		(15 "B.Paste" user)
		(5 "F.SilkS" user "F.Silkscreen")
		(7 "B.SilkS" user "B.Silkscreen")
		(1 "F.Mask" user)
		(3 "B.Mask" user)
		(17 "Dwgs.User" user "User.Drawings")
		(19 "Cmts.User" user "User.Comments")
		(21 "Eco1.User" user "User.Eco1")
		(23 "Eco2.User" user "User.Eco2")
		(25 "Edge.Cuts" user)
		(27 "Margin" user)
		(31 "F.CrtYd" user "F.Courtyard")
		(29 "B.CrtYd" user "B.Courtyard")
		(35 "F.Fab" user)
		(33 "B.Fab" user)
	)
	(footprint "antmicro-footprints:TP_SMD_1mm"
		(layer "F.Cu")
		(at 84.115 62.1908)
		(property "Reference" "TP1"
			(at -0.815 -0.6908 0)
			(layer "F.SilkS")
			(effects
				(font
					(size 0.7 0.7)
					(thickness 0.15)
				)
				(justify left bottom)
			)
		)
		(property "Value" "TP_1mm_SMD"
			(at 0 1.4 0)
			(layer "F.Fab")
			(effects
				(font
					(size 0.7 0.7)
					(thickness 0.15)
				)
				(justify left bottom)
			)
		)
		(property "Description" "Test point 1mm SMD"
			(at 0 0 0)
			(layer "F.Fab")
			(hide yes)
			(effects
				(font
					(size 1.27 1.27)
					(thickness 0.15)
				)
			)
		)
		(property "Author" "Antmicro"
			(at 0 0 0)
			(layer "F.Fab")
			(hide yes)
			(effects
				(font
					(size 1 1)
					(thickness 0.15)
				)
			)
		)
		(property "License" "Apache-2.0"
			(at 0 0 0)
			(layer "F.Fab")
			(hide yes)
			(effects
				(font
					(size 1 1)
					(thickness 0.15)
				)
			)
		)
		(property "MPN" ""
			(at 0 0 0)
			(layer "F.Fab")
			(hide yes)
			(effects
				(font
					(size 1 1)
					(thickness 0.15)
				)
			)
		)
		(property "Manufacturer" ""
			(at 0 0 0)
			(layer "F.Fab")
			(hide yes)
			(effects
				(font
					(size 1 1)
					(thickness 0.15)
				)
			)
		)
		(sheetname "/Power supply/")
		(sheetfile "power-supply.kicad_sch")
		(attr exclude_from_pos_files exclude_from_bom)
		(fp_circle
			(center 0 0)
			(end 0.6 0)
			(stroke
				(width 0.05)
				(type default)
			)
			(fill no)
			(layer "F.CrtYd")
		)
		(pad "1" smd circle
			(at 0 0)
			(size 1 1)
			(layers "F.Cu" "F.Mask")
			(net 228 "Net-(U25-EN)")
			(pinfunction "1")
			(pintype "passive")
		)
	)
	(footprint "antmicro-footprints:WSON-10-1EP_4x4mm_P0.8mm_EP2.6x3mm"
		(layer "F.Cu")
		(at 79.711 64.437 180)
		(property "Reference" "U25"
			(at 2.611 2.337 0)
			(layer "F.SilkS")
			(effects
				(font
					(size 0.7 0.7)
					(thickness 0.15)
				)
				(justify left bottom)
			)
		)
		(property "Value" "TPS54561QDPRRQ1"
			(at 0 3.4 0)
			(layer "F.Fab")
			(effects
				(font
					(size 0.7 0.7)
					(thickness 0.15)
				)
				(justify left bottom)
			)
		)
		(property "Datasheet" "https://www.ti.com/lit/ds/symlink/tps54561-q1.pdf?ts=1678720110394&ref_url=https%253A%252F%252Fwww.google.com%252F"
			(at 0 0 180)
			(layer "F.Fab")
			(hide yes)
			(effects
				(font
					(size 1.27 1.27)
					(thickness 0.15)
				)
			)
		)
		(property "Description" "DC/DC converter"
			(at 0 0 180)
			(layer "F.Fab")
			(hide yes)
			(effects
				(font
					(size 1.27 1.27)
					(thickness 0.15)
				)
			)
		)
		(property "Author" "Antmicro"
			(at 159.422 128.874 0)
			(layer "F.Fab")
			(hide yes)
			(effects
				(font
					(size 1 1)
					(thickness 0.15)
				)
			)
		)
		(property "License" "Apache-2.0"
			(at 159.422 128.874 0)
			(layer "F.Fab")
			(hide yes)
			(effects
				(font
					(size 1 1)
					(thickness 0.15)
				)
			)
		)
		(property "MPN" "TPS54561QDPRRQ1"
			(at 159.422 128.874 0)
			(layer "F.Fab")
			(hide yes)
			(effects
				(font
					(size 1 1)
					(thickness 0.15)
				)
			)
		)
		(property "Manufacturer" "Texas Instruments"
			(at 159.422 128.874 0)
			(layer "F.Fab")
			(hide yes)
			(effects
				(font
					(size 1 1)
					(thickness 0.15)
				)
			)
		)
		(sheetname "/Power supply/")
		(sheetfile "power-supply.kicad_sch")
		(attr smd)
		(fp_line
			(start 2.1 2.122)
			(end 2.1 1.975)
			(stroke
				(width 0.15)
				(type solid)
			)
			(layer "F.SilkS")
		)
		(fp_line
			(start 2.1 2.122)
			(end -2.1 2.122)
			(stroke
				(width 0.15)
				(type solid)
			)
			(layer "F.SilkS")
		)
		(fp_line
			(start 2.1 -2.123)
			(end 2.1 -1.975)
			(stroke
				(width 0.15)
				(type solid)
			)
			(layer "F.SilkS")
		)
		(fp_line
			(start -2.1 2.123)
			(end -2.1 1.975)
			(stroke
				(width 0.15)
				(type solid)
			)
			(layer "F.SilkS")
		)
		(fp_line
			(start -2.1 -2.123)
			(end 2.1 -2.123)
			(stroke
				(width 0.15)
				(type solid)
			)
			(layer "F.SilkS")
		)
		(fp_line
			(start -2.1 -2.123)
			(end -2.1 -1.975)
			(stroke
				(width 0.15)
				(type solid)
			)
			(layer "F.SilkS")
		)
		(fp_circle
			(center -2.325 -2.05)
			(end -2.275 -2.05)
			(stroke
				(width 0.15)
				(type solid)
			)
			(fill yes)
			(layer "F.SilkS")
		)
		(fp_rect
			(start -2.57 -2.2)
			(end 2.469 2.2)
			(stroke
				(width 0.05)
				(type solid)
			)
			(fill no)
			(layer "F.CrtYd")
		)
		(fp_line
			(start 2 2)
			(end -2 2)
			(stroke
				(width 0.15)
				(type solid)
			)
			(layer "F.Fab")
		)
		(fp_line
			(start 2 -2)
			(end 2 2)
			(stroke
				(width 0.15)
				(type solid)
			)
			(layer "F.Fab")
		)
		(fp_line
			(start -1.5 -2)
			(end 2 -2)
			(stroke
				(width 0.15)
				(type solid)
			)
			(layer "F.Fab")
		)
		(fp_line
			(start -2 2)
			(end -2 -1.5)
			(stroke
				(width 0.15)
				(type solid)
			)
			(layer "F.Fab")
		)
		(fp_line
			(start -2 -1.5)
			(end -1.5 -2)
			(stroke
				(width 0.15)
				(type solid)
			)
			(layer "F.Fab")
		)
		(pad "1" smd roundrect
			(at -1.9 -1.6 270)
			(size 0.3 0.6)
			(layers "F.Cu" "F.Mask" "F.Paste")
			(roundrect_rratio 0.1666666667)
			(net 110 "Net-(U25-BOOT)")
			(pinfunction "BOOT")
			(pintype "output")
		)
		(pad "2" smd roundrect
			(at -1.9 -0.8 270)
			(size 0.3 0.6)
			(layers "F.Cu" "F.Mask" "F.Paste")
			(roundrect_rratio 0.1666666667)
			(net 104 "/Power supply/VCC12V")
			(pinfunction "V_{DD}")
			(pintype "power_in")
		)
		(pad "3" smd roundrect
			(at -1.9 0 270)
			(size 0.3 0.6)
			(layers "F.Cu" "F.Mask" "F.Paste")
			(roundrect_rratio 0.1666666667)
			(net 228 "Net-(U25-EN)")
			(pinfunction "EN")
			(pintype "input")
		)
		(pad "4" smd roundrect
			(at -1.9 0.8 270)
			(size 0.3 0.6)
			(layers "F.Cu" "F.Mask" "F.Paste")
			(roundrect_rratio 0.1666666667)
			(net 106 "Net-(U25-SS{slash}TR)")
			(pinfunction "SS/TR")
			(pintype "input")
		)
		(pad "5" smd roundrect
			(at -1.9 1.6 270)
			(size 0.3 0.6)
			(layers "F.Cu" "F.Mask" "F.Paste")
			(roundrect_rratio 0.1666666667)
			(net 226 "Net-(U25-RT{slash}CLK)")
			(pinfunction "RT/CLK")
			(pintype "input")
		)
		(pad "6" smd roundrect
			(at 1.9 1.6 270)
			(size 0.3 0.6)
			(layers "F.Cu" "F.Mask" "F.Paste")
			(roundrect_rratio 0.1666666667)
			(net 227 "Net-(U25-FB)")
			(pinfunction "FB")
			(pintype "input")
		)
		(pad "7" smd roundrect
			(at 1.9 0.8 270)
			(size 0.3 0.6)
			(layers "F.Cu" "F.Mask" "F.Paste")
			(roundrect_rratio 0.1666666667)
			(net 107 "Net-(U25-COMP)")
			(pinfunction "COMP")
			(pintype "output")
		)
		(pad "8" smd roundrect
			(at 1.9 0 270)
			(size 0.3 0.6)
			(layers "F.Cu" "F.Mask" "F.Paste")
			(roundrect_rratio 0.1666666667)
			(net 1 "GND")
			(pinfunction "GND")
			(pintype "power_in")
		)
		(pad "9" smd roundrect
			(at 1.9 -0.8 270)
			(size 0.3 0.6)
			(layers "F.Cu" "F.Mask" "F.Paste")
			(roundrect_rratio 0.1666666667)
			(net 8 "Net-(D3-C)")
			(pinfunction "SW")
			(pintype "power_out")
		)
		(pad "10" smd roundrect
			(at 1.9 -1.6 270)
			(size 0.3 0.6)
			(layers "F.Cu" "F.Mask" "F.Paste")
			(roundrect_rratio 0.1666666667)
			(net 573 "/Power supply/5V0_PG")
			(pinfunction "PWRGD")
			(pintype "output")
		)
		(pad "11" smd roundrect
			(at 0 0 180)
			(size 2.6 3)
			(layers "F.Cu" "F.Mask" "F.Paste")
			(roundrect_rratio 0.01923076923)
			(net 1 "GND")
			(pinfunction "GND")
			(pintype "passive")
		)
	)
	(footprint "antmicro-footprints:PowerDI5"
		(layer "F.Cu")
		(at 69.2004 62.7048 180)
		(property "Reference" "D3"
			(at 0.0004 2.5048 0)
			(layer "F.SilkS")
			(effects
				(font
					(size 0.7 0.7)
					(thickness 0.15)
				)
				(justify right bottom)
			)
		)
		(property "Value" "PDS760"
			(at 0 3.4 0)
			(layer "F.Fab")
			(effects
				(font
					(size 0.7 0.7)
					(thickness 0.15)
				)
				(justify left bottom)
			)
		)
		(property "Datasheet" "https://www.diodes.com/assets/Datasheets/ds30470.pdf"
			(at 0 0 180)
			(layer "F.Fab")
			(hide yes)
			(effects
				(font
					(size 1.27 1.27)
					(thickness 0.15)
				)
			)
		)
		(property "Description" "Schottky Rectifier, POWERDI®, 60 V, 7 A, Single, PowerDI 5, 2 Pins, 620 mV"
			(at 0 0 180)
			(layer "F.Fab")
			(hide yes)
			(effects
				(font
					(size 1.27 1.27)
					(thickness 0.15)
				)
			)
		)
		(property "Author" "Antmicro"
			(at 138.4008 125.4096 0)
			(layer "F.Fab")
			(hide yes)
			(effects
				(font
					(size 1 1)
					(thickness 0.15)
				)
			)
		)
		(property "License" "Apache-2.0"
			(at 138.4008 125.4096 0)
			(layer "F.Fab")
			(hide yes)
			(effects
				(font
					(size 1 1)
					(thickness 0.15)
				)
			)
		)
		(property "MPN" "PDS760-13"
			(at 138.4008 125.4096 0)
			(layer "F.Fab")
			(hide yes)
			(effects
				(font
					(size 1 1)
					(thickness 0.15)
				)
			)
		)
		(property "Manufacturer" "Diodes Incorporated"
			(at 138.4008 125.4096 0)
			(layer "F.Fab")
			(hide yes)
			(effects
				(font
					(size 1 1)
					(thickness 0.15)
				)
			)
		)
		(sheetname "/Power supply/")
		(sheetfile "power-supply.kicad_sch")
		(attr smd)
		(fp_line
			(start 2.7 2.023)
			(end -2.7 2.023)
			(stroke
				(width 0.12)
				(type solid)
			)
			(layer "F.SilkS")
		)
		(fp_line
			(start 2.7 1.823)
			(end 2.7 2.023)
			(stroke
				(width 0.12)
				(type solid)
			)
			(layer "F.SilkS")
		)
		(fp_line
			(start 2.7 -2)
			(end 2.7 -1.8)
			(stroke
				(width 0.12)
				(type solid)
			)
			(layer "F.SilkS")
		)
		(fp_line
			(start -2.7 2.023)
			(end -2.7 1.823)
			(stroke
				(width 0.12)
				(type solid)
			)
			(layer "F.SilkS")
		)
		(fp_line
			(start -2.7 -1.8)
			(end -2.7 -2)
			(stroke
				(width 0.12)
				(type solid)
			)
			(layer "F.SilkS")
		)
		(fp_line
			(start -2.7 -2)
			(end 2.7 -2)
			(stroke
				(width 0.12)
				(type solid)
			)
			(layer "F.SilkS")
		)
		(fp_rect
			(start -3.702 -2.3)
			(end 3.7 2.3)
			(stroke
				(width 0.05)
				(type solid)
			)
			(fill no)
			(layer "F.CrtYd")
		)
		(pad "1" smd roundrect
			(at 1.1 0 90)
			(size 3.36 4.86)
			(layers "F.Cu" "F.Mask" "F.Paste")
			(roundrect_rratio 0.05)
			(net 8 "Net-(D3-C)")
			(pinfunction "C")
			(pintype "passive")
		)
		(pad "2" smd roundrect
			(at -2.862 -0.94 270)
			(size 1.39 1.4)
			(layers "F.Cu" "F.Mask" "F.Paste")
			(roundrect_rratio 0.25)
			(net 1 "GND")
			(pinfunction "A")
			(pintype "passive")
		)
		(pad "2" smd roundrect
			(at -2.862 0.941 90)
			(size 1.39 1.4)
			(layers "F.Cu" "F.Mask" "F.Paste")
			(roundrect_rratio 0.25)
			(net 1 "GND")
			(pinfunction "A")
			(pintype "passive")
		)
	)
	(footprint "antmicro-footprints:F_1206_3216Metric"
		(layer "F.Cu")
		(at 91.665 67.49 180)
		(property "Reference" "F1"
			(at -3.035 1.19 0)
			(layer "F.SilkS")
			(effects
				(font
					(size 0.7 0.7)
					(thickness 0.15)
				)
				(justify right bottom)
			)
		)
		(property "Value" "F_3A_1206"
			(at 0 2 0)
			(layer "F.Fab")
			(effects
				(font
					(size 0.7 0.7)
					(thickness 0.15)
				)
				(justify right bottom)
			)
		)
		(property "Datasheet" "https://www.littelfuse.com/~/media/electronics/datasheets/fuses/littelfuse_fuse_466_datasheet.pdf.pdf"
			(at 0 0 180)
			(layer "F.Fab")
			(hide yes)
			(effects
				(font
					(size 1.27 1.27)
					(thickness 0.15)
				)
			)
		)
		(property "Description" "Fuse, Surface Mount, 3 A, Very Fast Acting, 32 V, 32 V, 1206 (3216 Metric), 466"
			(at 0 0 180)
			(layer "F.Fab")
			(hide yes)
			(effects
				(font
					(size 1.27 1.27)
					(thickness 0.15)
				)
			)
		)
		(property "Author" "Antmicro"
			(at 183.33 134.98 0)
			(layer "F.Fab")
			(hide yes)
			(effects
				(font
					(size 1 1)
					(thickness 0.15)
				)
			)
		)
		(property "License" "Apache-2.0"
			(at 183.33 134.98 0)
			(layer "F.Fab")
			(hide yes)
			(effects
				(font
					(size 1 1)
					(thickness 0.15)
				)
			)
		)
		(property "MPN" "0466003.NR "
			(at 183.33 134.98 0)
			(layer "F.Fab")
			(hide yes)
			(effects
				(font
					(size 1 1)
					(thickness 0.15)
				)
			)
		)
		(property "Manufacturer" "Littelfuse"
			(at 183.33 134.98 0)
			(layer "F.Fab")
			(hide yes)
			(effects
				(font
					(size 1 1)
					(thickness 0.15)
				)
			)
		)
		(sheetname "/Power supply/")
		(sheetfile "power-supply.kicad_sch")
		(attr smd)
		(fp_line
			(start 0.8 0.901)
			(end -0.8 0.901)
			(stroke
				(width 0.15)
				(type solid)
			)
			(layer "F.SilkS")
		)
		(fp_line
			(start 0.8 -0.899)
			(end -0.8 -0.899)
			(stroke
				(width 0.15)
				(type solid)
			)
			(layer "F.SilkS")
		)
		(fp_rect
			(start -2.325 -1.15)
			(end 2.325 1.15)
			(stroke
				(width 0.05)
				(type default)
			)
			(fill no)
			(layer "F.CrtYd")
		)
		(fp_line
			(start 1.624 0.792)
			(end -1.677 0.792)
			(stroke
				(width 0.15)
				(type solid)
			)
			(layer "F.Fab")
		)
		(fp_line
			(start 1.624 -0.861)
			(end 1.624 0.792)
			(stroke
				(width 0.15)
				(type solid)
			)
			(layer "F.Fab")
		)
		(fp_line
			(start -1.677 0.792)
			(end -1.677 -0.861)
			(stroke
				(width 0.15)
				(type solid)
			)
			(layer "F.Fab")
		)
		(fp_line
			(start -1.677 -0.861)
			(end 1.624 -0.861)
			(stroke
				(width 0.15)
				(type solid)
			)
			(layer "F.Fab")
		)
		(pad "1" smd roundrect
			(at -1.5 0.001 180)
			(size 1.15 1.8)
			(layers "F.Cu" "F.Mask" "F.Paste")
			(roundrect_rratio 0.25)
			(net 59 "P12V_AUX")
			(pintype "passive")
		)
		(pad "2" smd roundrect
			(at 1.5 0.001 180)
			(size 1.15 1.8)
			(layers "F.Cu" "F.Mask" "F.Paste")
			(roundrect_rratio 0.25)
			(net 104 "/Power supply/VCC12V")
			(pintype "passive")
		)
	)
	(footprint "antmicro-footprints:R_0402_1005Metric"
		(layer "F.Cu")
		(at 73.925 64.025 -90)
		(descr "Resistor SMD 0402")
		(tags "resistor SMD 0402")
		(property "Reference" "R72"
			(at -4.025 -0.275 270)
			(layer "F.SilkS")
			(effects
				(font
					(size 0.7 0.7)
					(thickness 0.15)
				)
				(justify right bottom)
			)
		)
		(property "Value" "R_10k2_0402"
			(at 0 1.4 90)
			(layer "F.Fab")
			(effects
				(font
					(size 0.7 0.7)
					(thickness 0.15)
				)
				(justify right bottom)
			)
		)
		(property "Datasheet" "https://www.bourns.com/docs/product-datasheets/cr.pdf"
			(at 0 0 270)
			(layer "F.Fab")
			(hide yes)
			(effects
				(font
					(size 1.27 1.27)
					(thickness 0.15)
				)
			)
		)
		(property "Description" "SMD Chip Resistor"
			(at 0 0 270)
			(layer "F.Fab")
			(hide yes)
			(effects
				(font
					(size 1.27 1.27)
					(thickness 0.15)
				)
			)
		)
		(property "Author" "Antmicro"
			(at 9.9 137.95 0)
			(layer "F.Fab")
			(hide yes)
			(effects
				(font
					(size 1 1)
					(thickness 0.15)
				)
			)
		)
		(property "License" "Apache-2.0"
			(at 9.9 137.95 0)
			(layer "F.Fab")
			(hide yes)
			(effects
				(font
					(size 1 1)
					(thickness 0.15)
				)
			)
		)
		(property "MPN" "CR0402-FX-1022GLF"
			(at 9.9 137.95 0)
			(layer "F.Fab")
			(hide yes)
			(effects
				(font
					(size 1 1)
					(thickness 0.15)
				)
			)
		)
		(property "Manufacturer" "Bourns"
			(at 9.9 137.95 0)
			(layer "F.Fab")
			(hide yes)
			(effects
				(font
					(size 1 1)
					(thickness 0.15)
				)
			)
		)
		(property "Tolerance" "1%"
			(at 9.9 137.95 0)
			(layer "F.Fab")
			(hide yes)
			(effects
				(font
					(size 1 1)
					(thickness 0.15)
				)
			)
		)
		(property "Val" "10k2"
			(at 9.9 137.95 0)
			(layer "F.Fab")
			(hide yes)
			(effects
				(font
					(size 1 1)
					(thickness 0.15)
				)
			)
		)
		(sheetname "/Power supply/")
		(sheetfile "power-supply.kicad_sch")
		(attr smd)
		(fp_rect
			(start -0.925 -0.47)
			(end 0.925 0.47)
			(stroke
				(width 0.05)
				(type default)
			)
			(fill no)
			(layer "F.CrtYd")
		)
		(fp_rect
			(start -0.5 -0.25)
			(end 0.5 0.25)
			(stroke
				(width 0.15)
				(type solid)
			)
			(fill no)
			(layer "F.Fab")
		)
		(pad "1" smd roundrect
			(at -0.48 0 270)
			(size 0.59 0.64)
			(layers "F.Cu" "F.Mask" "F.Paste")
			(roundrect_rratio 0.25)
			(net 227 "Net-(U25-FB)")
			(pintype "passive")
		)
		(pad "2" smd roundrect
			(at 0.48 0 270)
			(size 0.59 0.64)
			(layers "F.Cu" "F.Mask" "F.Paste")
			(roundrect_rratio 0.25)
			(net 1 "GND")
			(pintype "passive")
		)
	)
	(footprint "antmicro-footprints:R_0402_1005Metric"
		(layer "F.Cu")
		(at 78.5 71.405 90)
		(descr "Resistor SMD 0402")
		(tags "resistor SMD 0402")
		(property "Reference" "R71"
			(at 0.105 -16.4 90)
			(layer "F.SilkS")
			(effects
				(font
					(size 0.7 0.7)
					(thickness 0.15)
				)
				(justify left bottom)
			)
		)
		(property "Value" "R_53k6_0402"
			(at 0 1.4 90)
			(layer "F.Fab")
			(effects
				(font
					(size 0.7 0.7)
					(thickness 0.15)
				)
				(justify left bottom)
			)
		)
		(property "Datasheet" "https://www.bourns.com/docs/product-datasheets/cr.pdf"
			(at 0 0 90)
			(layer "F.Fab")
			(hide yes)
			(effects
				(font
					(size 1.27 1.27)
					(thickness 0.15)
				)
			)
		)
		(property "Description" "SMD Chip Resistor"
			(at 0 0 90)
			(layer "F.Fab")
			(hide yes)
			(effects
				(font
					(size 1.27 1.27)
					(thickness 0.15)
				)
			)
		)
		(property "Author" "Antmicro"
			(at 149.905 -7.095 0)
			(layer "F.Fab")
			(hide yes)
			(effects
				(font
					(size 1 1)
					(thickness 0.15)
				)
			)
		)
		(property "License" "Apache-2.0"
			(at 149.905 -7.095 0)
			(layer "F.Fab")
			(hide yes)
			(effects
				(font
					(size 1 1)
					(thickness 0.15)
				)
			)
		)
		(property "MPN" "CR0402-FX-5362GLF"
			(at 149.905 -7.095 0)
			(layer "F.Fab")
			(hide yes)
			(effects
				(font
					(size 1 1)
					(thickness 0.15)
				)
			)
		)
		(property "Manufacturer" "Bourns"
			(at 149.905 -7.095 0)
			(layer "F.Fab")
			(hide yes)
			(effects
				(font
					(size 1 1)
					(thickness 0.15)
				)
			)
		)
		(property "Tolerance" "1%"
			(at 149.905 -7.095 0)
			(layer "F.Fab")
			(hide yes)
			(effects
				(font
					(size 1 1)
					(thickness 0.15)
				)
			)
		)
		(property "Val" "53k6"
			(at 149.905 -7.095 0)
			(layer "F.Fab")
			(hide yes)
			(effects
				(font
					(size 1 1)
					(thickness 0.15)
				)
			)
		)
		(sheetname "/Power supply/")
		(sheetfile "power-supply.kicad_sch")
		(attr smd)
		(fp_rect
			(start -0.925 -0.47)
			(end 0.925 0.47)
			(stroke
				(width 0.05)
				(type default)
			)
			(fill no)
			(layer "F.CrtYd")
		)
		(fp_rect
			(start -0.5 -0.25)
			(end 0.5 0.25)
			(stroke
				(width 0.15)
				(type solid)
			)
			(fill no)
			(layer "F.Fab")
		)
		(pad "1" smd roundrect
			(at -0.48 0 90)
			(size 0.59 0.64)
			(layers "F.Cu" "F.Mask" "F.Paste")
			(roundrect_rratio 0.25)
			(net 205 "Net-(R70-Pad2)")
			(pintype "passive")
		)
		(pad "2" smd roundrect
			(at 0.48 0 90)
			(size 0.59 0.64)
			(layers "F.Cu" "F.Mask" "F.Paste")
			(roundrect_rratio 0.25)
			(net 227 "Net-(U25-FB)")
			(pintype "passive")
		)
	)
)
